# BASEBOARD_FAB2 (Tioga Pass) — schematic netlist excerpt (pin names and nets, part order shuffled) for the footprints in the layout excerpt that follows; sources: Cadence DE-HDL packaged netlist, KiCad conversion of Wiwynn_Tioga_Pass_MB.brd

C2A16  CAP  100UF 4V 20% X5R  pkg 0805  page 228 : A = PVDDQ_KLM ; B = GND
C7B5  CAP  10UF 16V 10% X6S  pkg 0805  page 232 : A = VR_FET_SW_P12V_STBY_PVPP_DEF ; B = GND
C4D17  CAP  220PF 50V 10% X7R  pkg 0402LF  page 201 : A = A_TSENSE_PVCCIN_CPU0 ; B = GND

(kicad_pcb
	(version 20260206)
	(generator "pcbnew")
	(generator_version "10.0")
	(general
		(thickness 1.6)
		(legacy_teardrops no)
	)
	(paper "A4")
	(title_block
		(title "Wiwynn_Tioga_Pass_MB.brd")
		(comment 1 "Tioga Pass / footprints 538-540 of 4770")
	)
	(layers
		(0 "F.Cu" signal "TOP")
		(4 "In1.Cu" signal "L2GND")
		(6 "In2.Cu" signal "L3")
		(8 "In3.Cu" signal "L4GND")
		(10 "In4.Cu" signal "L5")
		(12 "In5.Cu" signal "L6GND")
		(14 "In6.Cu" signal "L7VCC")
		(16 "In7.Cu" signal "L8VCC")
		(18 "In8.Cu" signal "L9GND")
		(20 "In9.Cu" signal "L10")
		(22 "In10.Cu" signal "L11GND")
		(24 "In11.Cu" signal "L12")
		(26 "In12.Cu" signal "L13GND")
		(2 "B.Cu" signal "BOTTOM")
		(9 "F.Adhes" user "F.Adhesive")
		(11 "B.Adhes" user "B.Adhesive")
		(13 "F.Paste" user "Package Geometry/Pastemask Top")
		(15 "B.Paste" user "Package Geometry/Pastemask Bottom")
		(5 "F.SilkS" user "Ref Des/Silkscreen Top")
		(7 "B.SilkS" user "Ref Des/Silkscreen Bottom")
		(1 "F.Mask" user "Board Geometry/Soldermask Top")
		(3 "B.Mask" user "Board Geometry/Soldermask Bottom")
		(17 "Dwgs.User" user "User.Drawings")
		(19 "Cmts.User" user "User.Comments")
		(21 "Eco1.User" user "User.Eco1")
		(23 "Eco2.User" user "User.Eco2")
		(25 "Edge.Cuts" user "Board Geometry/Outline")
		(27 "Margin" user)
		(31 "F.CrtYd" user "Package Geometry/Place Bound Top")
		(29 "B.CrtYd" user "Package Geometry/Place Bound Bottom")
		(35 "F.Fab" user "Ref Des/Assembly Top")
		(33 "B.Fab" user "Ref Des/Assembly Bottom")
	)
	(footprint ""
		(layer "F.Cu")
		(at 94.447868 -140.100812 90)
		(property "Reference" "C2A16"
			(at 0 0 90)
			(layer "F.SilkS")
			(hide yes)
			(effects
				(font
					(size 1.27 1.27)
				)
			)
		)
		(property "Value" ""
			(at 0 0 90)
			(layer "F.Fab")
			(effects
				(font
					(size 1.27 1.27)
				)
			)
		)
		(duplicate_pad_numbers_are_jumpers no)
		(fp_poly
			(pts
				(xy -0.7239 -0.2159) (xy 0.7239 -0.2159) (xy 0.7239 1.9939) (xy -0.7239 1.9939)
			)
			(stroke
				(width 0)
				(type default)
			)
			(fill no)
			(layer "F.CrtYd")
		)
		(fp_line
			(start 0.7239 -0.2159)
			(end -0.7239 -0.2159)
			(stroke
				(width 0.1)
				(type default)
			)
			(layer "F.Fab")
		)
		(fp_line
			(start -0.7239 -0.2159)
			(end -0.7239 1.9939)
			(stroke
				(width 0.1)
				(type default)
			)
			(layer "F.Fab")
		)
		(fp_line
			(start 0.7239 1.9939)
			(end 0.7239 -0.2159)
			(stroke
				(width 0.1)
				(type default)
			)
			(layer "F.Fab")
		)
		(fp_line
			(start -0.7239 1.9939)
			(end 0.7239 1.9939)
			(stroke
				(width 0.1)
				(type default)
			)
			(layer "F.Fab")
		)
		(pad "1" smd rect
			(at 0 0 90)
			(size 1.27 1.016)
			(layers "F.Cu" "F.Mask" "F.Paste")
			(net "PVDDQ_KLM")
		)
		(pad "2" smd rect
			(at 0 1.778 90)
			(size 1.27 1.016)
			(layers "F.Cu" "F.Mask" "F.Paste")
			(net "GND")
		)
		(zone
			(layer "F.Cu")
			(hatch none 0.5)
			(connect_pads
				(clearance 0)
			)
			(min_thickness 0.25)
			(keepout
				(tracks not_allowed)
				(vias allowed)
				(pads allowed)
				(copperpour not_allowed)
				(footprints allowed)
			)
			(placement
				(enabled no)
				(sheetname "")
			)
			(fill
				(thermal_gap 0.5)
				(thermal_bridge_width 0.5)
				(island_removal_mode 0)
			)
			(polygon
				(pts
					(xy 94.955868 -139.465812) (xy 94.955868 -140.735812) (xy 95.717868 -140.735812) (xy 95.717868 -139.465812)
				)
			)
		)
	)
	(footprint ""
		(layer "F.Cu")
		(at 349.631 -133.223 180)
		(property "Reference" "C7B5"
			(at 0 0 180)
			(layer "F.SilkS")
			(hide yes)
			(effects
				(font
					(size 1.27 1.27)
				)
			)
		)
		(property "Value" ""
			(at 0 0 180)
			(layer "F.Fab")
			(effects
				(font
					(size 1.27 1.27)
				)
			)
		)
		(duplicate_pad_numbers_are_jumpers no)
		(fp_poly
			(pts
				(xy -0.7239 -0.2159) (xy 0.7239 -0.2159) (xy 0.7239 1.9939) (xy -0.7239 1.9939)
			)
			(stroke
				(width 0)
				(type default)
			)
			(fill no)
			(layer "F.CrtYd")
		)
		(fp_line
			(start 0.7239 1.9939)
			(end 0.7239 -0.2159)
			(stroke
				(width 0.1)
				(type default)
			)
			(layer "F.Fab")
		)
		(fp_line
			(start 0.7239 -0.2159)
			(end -0.7239 -0.2159)
			(stroke
				(width 0.1)
				(type default)
			)
			(layer "F.Fab")
		)
		(fp_line
			(start -0.7239 1.9939)
			(end 0.7239 1.9939)
			(stroke
				(width 0.1)
				(type default)
			)
			(layer "F.Fab")
		)
		(fp_line
			(start -0.7239 -0.2159)
			(end -0.7239 1.9939)
			(stroke
				(width 0.1)
				(type default)
			)
			(layer "F.Fab")
		)
		(pad "1" smd rect
			(at 0 0 180)
			(size 1.27 1.016)
			(layers "F.Cu" "F.Mask" "F.Paste")
			(net "VR_FET_SW_P12V_STBY_PVPP_DEF")
		)
		(pad "2" smd rect
			(at 0 1.778 180)
			(size 1.27 1.016)
			(layers "F.Cu" "F.Mask" "F.Paste")
			(net "GND")
		)
		(zone
			(layer "F.Cu")
			(hatch none 0.5)
			(connect_pads
				(clearance 0)
			)
			(min_thickness 0.25)
			(keepout
				(tracks not_allowed)
				(vias allowed)
				(pads allowed)
				(copperpour not_allowed)
				(footprints allowed)
			)
			(placement
				(enabled no)
				(sheetname "")
			)
			(fill
				(thermal_gap 0.5)
				(thermal_bridge_width 0.5)
				(island_removal_mode 0)
			)
			(polygon
				(pts
					(xy 350.266 -133.731) (xy 348.996 -133.731) (xy 348.996 -134.493) (xy 350.266 -134.493)
				)
			)
		)
	)
	(footprint ""
		(layer "F.Cu")
		(at 184.2516 -75.4253 180)
		(property "Reference" "C4D17"
			(at 0 0 180)
			(layer "F.SilkS")
			(hide yes)
			(effects
				(font
					(size 1.27 1.27)
				)
			)
		)
		(property "Value" ""
			(at 0 0 180)
			(layer "F.Fab")
			(effects
				(font
					(size 1.27 1.27)
				)
			)
		)
		(duplicate_pad_numbers_are_jumpers no)
		(fp_rect
			(start 0.3048 -0.1016)
			(end -0.3048 0.9906)
			(stroke
				(width 0)
				(type default)
			)
			(fill no)
			(layer "F.CrtYd")
		)
		(fp_line
			(start 0.3048 0.9906)
			(end 0.3048 -0.1016)
			(stroke
				(width 0.1)
				(type default)
			)
			(layer "F.Fab")
		)
		(fp_line
			(start 0.3048 -0.1016)
			(end -0.3048 -0.1016)
			(stroke
				(width 0.1)
				(type default)
			)
			(layer "F.Fab")
		)
		(fp_line
			(start -0.3048 0.9906)
			(end 0.3048 0.9906)
			(stroke
				(width 0.1)
				(type default)
			)
			(layer "F.Fab")
		)
		(fp_line
			(start -0.3048 -0.1016)
			(end -0.3048 0.9906)
			(stroke
				(width 0.1)
				(type default)
			)
			(layer "F.Fab")
		)
		(pad "1" smd rect
			(at 0 0 180)
			(size 0.508 0.508)
			(layers "F.Cu" "F.Mask" "F.Paste")
			(net "A_TSENSE_PVCCIN_CPU0")
		)
		(pad "2" smd rect
			(at 0 0.889 180)
			(size 0.508 0.508)
			(layers "F.Cu" "F.Mask" "F.Paste")
			(net "GND")
		)
		(zone
			(layer "F.Cu")
			(hatch none 0.5)
			(connect_pads
				(clearance 0)
			)
			(min_thickness 0.25)
			(keepout
				(tracks not_allowed)
				(vias allowed)
				(pads allowed)
				(copperpour not_allowed)
				(footprints allowed)
			)
			(placement
				(enabled no)
				(sheetname "")
			)
			(fill
				(thermal_gap 0.5)
				(thermal_bridge_width 0.5)
				(island_removal_mode 0)
			)
			(polygon
				(pts
					(xy 183.9976 -75.6793) (xy 184.5056 -75.6793) (xy 184.5056 -76.0603) (xy 183.9976 -76.0603)
				)
			)
		)
		(zone
			(layer "F.Cu")
			(hatch none 0.5)
			(connect_pads
				(clearance 0)
			)
			(min_thickness 0.25)
			(keepout
				(tracks allowed)
				(vias not_allowed)
				(pads allowed)
				(copperpour not_allowed)
				(footprints allowed)
			)
			(placement
				(enabled no)
				(sheetname "")
			)
			(fill
				(thermal_gap 0.5)
				(thermal_bridge_width 0.5)
				(island_removal_mode 0)
			)
			(polygon
				(pts
					(xy 183.9976 -75.6793) (xy 184.5056 -75.6793) (xy 184.5056 -76.0603) (xy 183.9976 -76.0603)
				)
			)
		)
	)
)
